(kicad_pcb
	(version 20260206)
	(generator "pcbnew")
	(generator_version "10.0")
	(general
		(thickness 1.6)
		(legacy_teardrops no)
	)
	(paper "A4")
	(title_block
		(title "baseboard — 13948-1b.1110WZS1818.brd")
		(comment 1 "Honey Badger (Wiwynn) / footprints 823-828 of 2523")
	)
	(layers
		(0 "F.Cu" signal "TOP")
		(4 "In1.Cu" signal "L2GND")
		(6 "In2.Cu" signal "L3")
		(8 "In3.Cu" signal "L4VCC")
		(10 "In4.Cu" signal "L5VCC")
		(12 "In5.Cu" signal "L6")
		(14 "In6.Cu" signal "L7GND")
		(2 "B.Cu" signal "BOTTOM")
		(9 "F.Adhes" user "F.Adhesive")
		(11 "B.Adhes" user "B.Adhesive")
		(13 "F.Paste" user "Package Geometry/Pastemask Top")
		(15 "B.Paste" user "Package Geometry/Pastemask Bottom")
		(5 "F.SilkS" user "Ref Des/Silkscreen Top")
		(7 "B.SilkS" user "Ref Des/Silkscreen Bottom")
		(1 "F.Mask" user "Board Geometry/Soldermask Top")
		(3 "B.Mask" user "Board Geometry/Soldermask Bottom")
		(17 "Dwgs.User" user "User.Drawings")
		(19 "Cmts.User" user "User.Comments")
		(21 "Eco1.User" user "User.Eco1")
		(23 "Eco2.User" user "User.Eco2")
		(25 "Edge.Cuts" user "Board Geometry/Outline")
		(27 "Margin" user)
		(31 "F.CrtYd" user "Package Geometry/Place Bound Top")
		(29 "B.CrtYd" user "Package Geometry/Place Bound Bottom")
		(35 "F.Fab" user "Ref Des/Assembly Top")
		(33 "B.Fab" user "Ref Des/Assembly Bottom")
	)
	(footprint ""
		(layer "F.Cu")
		(at 204.724 -185.42)
		(property "Reference" "R477"
			(at 0 0 0)
			(layer "F.SilkS")
			(hide yes)
			(effects
				(font
					(size 1.27 1.27)
				)
			)
		)
		(property "Value" "4K7R2F-GP"
			(at 0.064008 -3.993896 0)
			(unlocked yes)
			(layer "F.Fab")
			(hide yes)
			(effects
				(font
					(size 1.016 1.016)
					(thickness 0.1524)
				)
			)
		)
		(property "Device Type" "R402H16"
			(at 0.064008 -5.517896 0)
			(unlocked yes)
			(layer "F.Fab")
			(hide yes)
			(effects
				(font
					(size 1.016 1.016)
					(thickness 0.1524)
				)
			)
		)
		(duplicate_pad_numbers_are_jumpers no)
		(fp_line
			(start -0.508 -0.9398)
			(end -0.508 0.9398)
			(stroke
				(width 0.1524)
				(type default)
			)
			(layer "F.SilkS")
		)
		(fp_line
			(start 0.508 -0.9398)
			(end -0.508 -0.9398)
			(stroke
				(width 0.1524)
				(type default)
			)
			(layer "F.SilkS")
		)
		(fp_rect
			(start -0.508 0.9398)
			(end 0.508 -0.9398)
			(stroke
				(width 0)
				(type default)
			)
			(fill no)
			(layer "F.CrtYd")
		)
		(fp_rect
			(start -0.508 0.9398)
			(end 0.508 -0.9398)
			(stroke
				(width 0)
				(type default)
			)
			(fill no)
			(layer "F.Fab")
		)
		(pad "1" smd custom
			(at 0 -0.4445)
			(size 0.1397 0.1397)
			(layers "F.Cu" "F.Mask" "F.Paste")
			(net "DIVIDER 1_IN")
			(options
				(clearance outline)
				(anchor circle)
			)
			(primitives
				(gr_poly
					(pts
						(arc
							(start -0.1778 -0.2794)
							(mid -0.249642 -0.249642)
							(end -0.2794 -0.1778)
						)
						(arc
							(start -0.2794 0.1778)
							(mid -0.249642 0.249642)
							(end -0.1778 0.2794)
						)
						(arc
							(start 0.1778 0.2794)
							(mid 0.249642 0.249642)
							(end 0.2794 0.1778)
						)
						(arc
							(start 0.2794 -0.1778)
							(mid 0.249642 -0.249642)
							(end 0.1778 -0.2794)
						)
					)
					(width 0)
					(fill yes)
				)
			)
		)
		(pad "2" smd custom
			(at 0 0.4445)
			(size 0.1397 0.1397)
			(layers "F.Cu" "F.Mask" "F.Paste")
			(net "DIVIDER 2_IN")
			(options
				(clearance outline)
				(anchor circle)
			)
			(primitives
				(gr_poly
					(pts
						(arc
							(start -0.1778 -0.2794)
							(mid -0.249642 -0.249642)
							(end -0.2794 -0.1778)
						)
						(arc
							(start -0.2794 0.1778)
							(mid -0.249642 0.249642)
							(end -0.1778 0.2794)
						)
						(arc
							(start 0.1778 0.2794)
							(mid 0.249642 0.249642)
							(end 0.2794 0.1778)
						)
						(arc
							(start 0.2794 -0.1778)
							(mid 0.249642 -0.249642)
							(end 0.1778 -0.2794)
						)
					)
					(width 0)
					(fill yes)
				)
			)
		)
	)
	(footprint ""
		(layer "F.Cu")
		(at 93.218 -112.014 180)
		(property "Reference" "SC1235"
			(at 0 0 180)
			(layer "F.SilkS")
			(hide yes)
			(effects
				(font
					(size 1.27 1.27)
				)
			)
		)
		(property "Value" "SCD1U6D3V1KX-GP"
			(at -2.8321 -1.7399 180)
			(unlocked yes)
			(layer "F.Fab")
			(hide yes)
			(effects
				(font
					(size 1.016 1.016)
					(thickness 0.1524)
				)
			)
		)
		(property "Device Type" "C0201H13"
			(at -2.8321 -3.2639 180)
			(unlocked yes)
			(layer "F.Fab")
			(hide yes)
			(effects
				(font
					(size 1.016 1.016)
					(thickness 0.1524)
				)
			)
		)
		(duplicate_pad_numbers_are_jumpers no)
		(fp_rect
			(start -0.2794 0.6477)
			(end 0.2794 -0.6477)
			(stroke
				(width 0)
				(type default)
			)
			(fill no)
			(layer "F.CrtYd")
		)
		(fp_rect
			(start -0.2794 0.6477)
			(end 0.2794 -0.6477)
			(stroke
				(width 0)
				(type default)
			)
			(fill no)
			(layer "F.Fab")
		)
		(pad "1" smd custom
			(at 0 -0.2794 180)
			(size 0.0762 0.0762)
			(layers "F.Cu" "F.Mask" "F.Paste")
			(net "P1V8_E")
			(options
				(clearance outline)
				(anchor circle)
			)
			(primitives
				(gr_poly
					(pts
						(arc
							(start 0.1524 -0.127)
							(mid 0.137521 -0.162921)
							(end 0.1016 -0.1778)
						)
						(arc
							(start -0.1016 -0.1778)
							(mid -0.137521 -0.162921)
							(end -0.1524 -0.127)
						)
						(arc
							(start -0.1524 0.127)
							(mid -0.137521 0.162921)
							(end -0.1016 0.1778)
						)
						(arc
							(start 0.1016 0.1778)
							(mid 0.137521 0.162921)
							(end 0.1524 0.127)
						)
					)
					(width 0)
					(fill yes)
				)
			)
		)
		(pad "2" smd custom
			(at 0 0.2794 180)
			(size 0.0762 0.0762)
			(layers "F.Cu" "F.Mask" "F.Paste")
			(net "GND")
			(options
				(clearance outline)
				(anchor circle)
			)
			(primitives
				(gr_poly
					(pts
						(arc
							(start 0.1524 -0.127)
							(mid 0.137521 -0.162921)
							(end 0.1016 -0.1778)
						)
						(arc
							(start -0.1016 -0.1778)
							(mid -0.137521 -0.162921)
							(end -0.1524 -0.127)
						)
						(arc
							(start -0.1524 0.127)
							(mid -0.137521 0.162921)
							(end -0.1016 0.1778)
						)
						(arc
							(start 0.1016 0.1778)
							(mid 0.137521 0.162921)
							(end 0.1524 0.127)
						)
					)
					(width 0)
					(fill yes)
				)
			)
		)
	)
	(footprint ""
		(layer "F.Cu")
		(at 26.224738 -172.926756)
		(property "Reference" "SU69"
			(at 0 0 0)
			(layer "F.SilkS")
			(hide yes)
			(effects
				(font
					(size 1.27 1.27)
				)
			)
		)
		(property "Value" "SNLVC8T245DGVR-GP"
			(at 0 -11.1252 0)
			(unlocked yes)
			(layer "F.Fab")
			(hide yes)
			(effects
				(font
					(size 1.016 1.016)
					(thickness 0.1524)
				)
			)
		)
		(property "Device Type" "TVSOP24H48"
			(at 0 -12.6492 0)
			(unlocked yes)
			(layer "F.Fab")
			(hide yes)
			(effects
				(font
					(size 1.016 1.016)
					(thickness 0.1524)
				)
			)
		)
		(duplicate_pad_numbers_are_jumpers no)
		(fp_line
			(start -2.9337 -1.397)
			(end -2.9337 1.397)
			(stroke
				(width 0.1524)
				(type default)
			)
			(layer "F.SilkS")
		)
		(fp_line
			(start -2.9337 -0.3683)
			(end -2.5654 0)
			(stroke
				(width 0.1524)
				(type default)
			)
			(layer "F.SilkS")
		)
		(fp_line
			(start -2.9337 1.397)
			(end 2.2987 1.397)
			(stroke
				(width 0.1524)
				(type default)
			)
			(layer "F.SilkS")
		)
		(fp_line
			(start -2.7559 1.397)
			(end -2.7559 3.8354)
			(stroke
				(width 0.508)
				(type default)
			)
			(layer "F.SilkS")
		)
		(fp_line
			(start -2.5654 0)
			(end -2.9337 0.3683)
			(stroke
				(width 0.1524)
				(type default)
			)
			(layer "F.SilkS")
		)
		(fp_line
			(start 2.2987 -1.397)
			(end -2.9337 -1.397)
			(stroke
				(width 0.1524)
				(type default)
			)
			(layer "F.SilkS")
		)
		(fp_line
			(start 2.2987 1.397)
			(end 2.2987 -1.397)
			(stroke
				(width 0.1524)
				(type default)
			)
			(layer "F.SilkS")
		)
		(fp_rect
			(start -3.0099 4.0894)
			(end 3.0099 -4.0894)
			(stroke
				(width 0)
				(type default)
			)
			(fill no)
			(layer "F.CrtYd")
		)
		(fp_poly
			(pts
				(xy -3.0099 -4.0894) (xy 3.0099 -4.0894) (xy 3.0099 4.0894) (xy -3.0099 4.0894)
			)
			(stroke
				(width 0)
				(type default)
			)
			(fill no)
			(layer "F.Fab")
		)
		(pad "1" smd rect
			(at -2.19964 2.8194)
			(size 0.2032 1.524)
			(layers "F.Cu" "F.Mask" "F.Paste")
			(net "P1V8_E")
		)
		(pad "2" smd rect
			(at -1.79959 2.8194)
			(size 0.2032 1.524)
			(layers "F.Cu" "F.Mask" "F.Paste")
			(net "GND")
		)
		(pad "3" smd rect
			(at -1.39954 2.8194)
			(size 0.2032 1.524)
			(layers "F.Cu" "F.Mask" "F.Paste")
			(net "SAS_HDD_LED20")
		)
		(pad "4" smd rect
			(at -0.99949 2.8194)
			(size 0.2032 1.524)
			(layers "F.Cu" "F.Mask" "F.Paste")
			(net "SAS_HDD_LED21")
		)
		(pad "5" smd rect
			(at -0.59944 2.8194)
			(size 0.2032 1.524)
			(layers "F.Cu" "F.Mask" "F.Paste")
			(net "SAS_HDD_LED22")
		)
		(pad "6" smd rect
			(at -0.19939 2.8194)
			(size 0.2032 1.524)
			(layers "F.Cu" "F.Mask" "F.Paste")
			(net "SAS_HDD_LED23")
		)
		(pad "7" smd rect
			(at 0.19939 2.8194)
			(size 0.2032 1.524)
			(layers "F.Cu" "F.Mask" "F.Paste")
			(net "SAS_HDD_LED0")
		)
		(pad "8" smd rect
			(at 0.59944 2.8194)
			(size 0.2032 1.524)
			(layers "F.Cu" "F.Mask" "F.Paste")
			(net "SAS_HDD_LED1")
		)
		(pad "9" smd rect
			(at 0.99949 2.8194)
			(size 0.2032 1.524)
			(layers "F.Cu" "F.Mask" "F.Paste")
			(net "SAS_HDD_LED2")
		)
		(pad "10" smd rect
			(at 1.39954 2.8194)
			(size 0.2032 1.524)
			(layers "F.Cu" "F.Mask" "F.Paste")
			(net "SAS_HDD_LED3")
		)
		(pad "11" smd rect
			(at 1.79959 2.8194)
			(size 0.2032 1.524)
			(layers "F.Cu" "F.Mask" "F.Paste")
			(net "GND")
		)
		(pad "12" smd rect
			(at 2.19964 2.8194)
			(size 0.2032 1.524)
			(layers "F.Cu" "F.Mask" "F.Paste")
			(net "GND")
		)
		(pad "13" smd rect
			(at 2.19964 -2.8194)
			(size 0.2032 1.524)
			(layers "F.Cu" "F.Mask" "F.Paste")
			(net "GND")
		)
		(pad "14" smd rect
			(at 1.79959 -2.8194)
			(size 0.2032 1.524)
			(layers "F.Cu" "F.Mask" "F.Paste")
			(net "SAS_HDD_PRE7")
		)
		(pad "15" smd rect
			(at 1.39954 -2.8194)
			(size 0.2032 1.524)
			(layers "F.Cu" "F.Mask" "F.Paste")
			(net "SAS_HDD_PRE6")
		)
		(pad "16" smd rect
			(at 0.99949 -2.8194)
			(size 0.2032 1.524)
			(layers "F.Cu" "F.Mask" "F.Paste")
			(net "SAS_HDD_PRE5")
		)
		(pad "17" smd rect
			(at 0.59944 -2.8194)
			(size 0.2032 1.524)
			(layers "F.Cu" "F.Mask" "F.Paste")
			(net "SAS_HDD_PRE4")
		)
		(pad "18" smd rect
			(at 0.19939 -2.8194)
			(size 0.2032 1.524)
			(layers "F.Cu" "F.Mask" "F.Paste")
			(net "SAS_HDD_PRE3")
		)
		(pad "19" smd rect
			(at -0.19939 -2.8194)
			(size 0.2032 1.524)
			(layers "F.Cu" "F.Mask" "F.Paste")
			(net "SAS_HDD_PRE2")
		)
		(pad "20" smd rect
			(at -0.59944 -2.8194)
			(size 0.2032 1.524)
			(layers "F.Cu" "F.Mask" "F.Paste")
			(net "SAS_HDD_PRE1")
		)
		(pad "21" smd rect
			(at -0.99949 -2.8194)
			(size 0.2032 1.524)
			(layers "F.Cu" "F.Mask" "F.Paste")
			(net "SAS_HDD_PRE0")
		)
		(pad "22" smd rect
			(at -1.39954 -2.8194)
			(size 0.2032 1.524)
			(layers "F.Cu" "F.Mask" "F.Paste")
			(net "GND")
		)
		(pad "23" smd rect
			(at -1.79959 -2.8194)
			(size 0.2032 1.524)
			(layers "F.Cu" "F.Mask" "F.Paste")
			(net "P3V3_STBY")
		)
		(pad "24" smd rect
			(at -2.19964 -2.8194)
			(size 0.2032 1.524)
			(layers "F.Cu" "F.Mask" "F.Paste")
			(net "P3V3_STBY")
		)
	)
	(footprint ""
		(layer "F.Cu")
		(at 91.929966 -69.342 180)
		(property "Reference" "SC1002"
			(at 0 0 180)
			(layer "F.SilkS")
			(hide yes)
			(effects
				(font
					(size 1.27 1.27)
				)
			)
		)
		(property "Value" "SCD1U16V2KX-3GP"
			(at 1.1811 -2.7051 180)
			(unlocked yes)
			(layer "F.Fab")
			(hide yes)
			(effects
				(font
					(size 1.016 1.016)
					(thickness 0.1524)
				)
			)
		)
		(property "Device Type" "C402H22"
			(at 1.1811 -4.2291 180)
			(unlocked yes)
			(layer "F.Fab")
			(hide yes)
			(effects
				(font
					(size 1.016 1.016)
					(thickness 0.1524)
				)
			)
		)
		(duplicate_pad_numbers_are_jumpers no)
		(fp_rect
			(start -0.4318 0.9525)
			(end 0.4318 -0.9525)
			(stroke
				(width 0)
				(type default)
			)
			(fill no)
			(layer "F.CrtYd")
		)
		(fp_rect
			(start -0.4318 0.9525)
			(end 0.4318 -0.9525)
			(stroke
				(width 0)
				(type default)
			)
			(fill no)
			(layer "F.Fab")
		)
		(pad "1" smd custom
			(at 0 -0.4445 180)
			(size 0.1524 0.1524)
			(layers "F.Cu" "F.Mask" "F.Paste")
			(net "P1V8_C")
			(options
				(clearance outline)
				(anchor circle)
			)
			(primitives
				(gr_poly
					(pts
						(arc
							(start 0.3048 -0.2032)
							(mid 0.275042 -0.275042)
							(end 0.2032 -0.3048)
						)
						(arc
							(start -0.2032 -0.3048)
							(mid -0.275042 -0.275042)
							(end -0.3048 -0.2032)
						)
						(arc
							(start -0.3048 0.2032)
							(mid -0.275042 0.275042)
							(end -0.2032 0.3048)
						)
						(arc
							(start 0.2032 0.3048)
							(mid 0.275042 0.275042)
							(end 0.3048 0.2032)
						)
					)
					(width 0)
					(fill yes)
				)
			)
		)
		(pad "2" smd custom
			(at 0 0.4445 180)
			(size 0.1524 0.1524)
			(layers "F.Cu" "F.Mask" "F.Paste")
			(net "GND")
			(options
				(clearance outline)
				(anchor circle)
			)
			(primitives
				(gr_poly
					(pts
						(arc
							(start 0.3048 -0.2032)
							(mid 0.275042 -0.275042)
							(end 0.2032 -0.3048)
						)
						(arc
							(start -0.2032 -0.3048)
							(mid -0.275042 -0.275042)
							(end -0.3048 -0.2032)
						)
						(arc
							(start -0.3048 0.2032)
							(mid -0.275042 0.275042)
							(end -0.2032 0.3048)
						)
						(arc
							(start 0.2032 0.3048)
							(mid 0.275042 0.275042)
							(end 0.3048 0.2032)
						)
					)
					(width 0)
					(fill yes)
				)
			)
		)
	)
	(footprint ""
		(layer "F.Cu")
		(at 12.142216 -237.29188 180)
		(property "Reference" "SR262"
			(at 0 0 180)
			(layer "F.SilkS")
			(hide yes)
			(effects
				(font
					(size 1.27 1.27)
				)
			)
		)
		(property "Value" "0R2J-2-GP"
			(at 0.064008 -3.993896 180)
			(unlocked yes)
			(layer "F.Fab")
			(hide yes)
			(effects
				(font
					(size 1.016 1.016)
					(thickness 0.1524)
				)
			)
		)
		(property "Device Type" "R402H16"
			(at 0.064008 -5.517896 180)
			(unlocked yes)
			(layer "F.Fab")
			(hide yes)
			(effects
				(font
					(size 1.016 1.016)
					(thickness 0.1524)
				)
			)
		)
		(duplicate_pad_numbers_are_jumpers no)
		(fp_line
			(start 0.508 -0.9398)
			(end -0.508 -0.9398)
			(stroke
				(width 0.1524)
				(type default)
			)
			(layer "F.SilkS")
		)
		(fp_line
			(start -0.508 -0.9398)
			(end -0.508 0.9398)
			(stroke
				(width 0.1524)
				(type default)
			)
			(layer "F.SilkS")
		)
		(fp_rect
			(start -0.508 0.9398)
			(end 0.508 -0.9398)
			(stroke
				(width 0)
				(type default)
			)
			(fill no)
			(layer "F.CrtYd")
		)
		(fp_rect
			(start -0.508 0.9398)
			(end 0.508 -0.9398)
			(stroke
				(width 0)
				(type default)
			)
			(fill no)
			(layer "F.Fab")
		)
		(pad "1" smd custom
			(at 0 -0.4445 180)
			(size 0.1397 0.1397)
			(layers "F.Cu" "F.Mask" "F.Paste")
			(net "PCIE_MATED#_AB")
			(options
				(clearance outline)
				(anchor circle)
			)
			(primitives
				(gr_poly
					(pts
						(arc
							(start -0.1778 -0.2794)
							(mid -0.249642 -0.249642)
							(end -0.2794 -0.1778)
						)
						(arc
							(start -0.2794 0.1778)
							(mid -0.249642 0.249642)
							(end -0.1778 0.2794)
						)
						(arc
							(start 0.1778 0.2794)
							(mid 0.249642 0.249642)
							(end 0.2794 0.1778)
						)
						(arc
							(start 0.2794 -0.1778)
							(mid 0.249642 -0.249642)
							(end 0.1778 -0.2794)
						)
					)
					(width 0)
					(fill yes)
				)
			)
		)
		(pad "2" smd custom
			(at 0 0.4445 180)
			(size 0.1397 0.1397)
			(layers "F.Cu" "F.Mask" "F.Paste")
			(net "PCIE_MATED#")
			(options
				(clearance outline)
				(anchor circle)
			)
			(primitives
				(gr_poly
					(pts
						(arc
							(start -0.1778 -0.2794)
							(mid -0.249642 -0.249642)
							(end -0.2794 -0.1778)
						)
						(arc
							(start -0.2794 0.1778)
							(mid -0.249642 0.249642)
							(end -0.1778 0.2794)
						)
						(arc
							(start 0.1778 0.2794)
							(mid 0.249642 0.249642)
							(end 0.2794 0.1778)
						)
						(arc
							(start 0.2794 -0.1778)
							(mid 0.249642 -0.249642)
							(end 0.1778 -0.2794)
						)
					)
					(width 0)
					(fill yes)
				)
			)
		)
	)
	(footprint ""
		(layer "F.Cu")
		(at 215.265 -220.599 90)
		(property "Reference" "C83"
			(at 0 0 90)
			(layer "F.SilkS")
			(hide yes)
			(effects
				(font
					(size 1.27 1.27)
				)
			)
		)
		(property "Value" "SCD1U16V2KX-3GP"
			(at 1.1811 -2.7051 90)
			(unlocked yes)
			(layer "F.Fab")
			(hide yes)
			(effects
				(font
					(size 1.016 1.016)
					(thickness 0.1524)
				)
			)
		)
		(property "Device Type" "C402H22"
			(at 1.1811 -4.2291 90)
			(unlocked yes)
			(layer "F.Fab")
			(hide yes)
			(effects
				(font
					(size 1.016 1.016)
					(thickness 0.1524)
				)
			)
		)
		(duplicate_pad_numbers_are_jumpers no)
		(fp_rect
			(start -0.4318 0.9525)
			(end 0.4318 -0.9525)
			(stroke
				(width 0)
				(type default)
			)
			(fill no)
			(layer "F.CrtYd")
		)
		(fp_rect
			(start -0.4318 0.9525)
			(end 0.4318 -0.9525)
			(stroke
				(width 0)
				(type default)
			)
			(fill no)
			(layer "F.Fab")
		)
		(pad "1" smd custom
			(at 0 -0.4445 90)
			(size 0.1524 0.1524)
			(layers "F.Cu" "F.Mask" "F.Paste")
			(net "P3V3_STBY")
			(options
				(clearance outline)
				(anchor circle)
			)
			(primitives
				(gr_poly
					(pts
						(arc
							(start 0.3048 -0.2032)
							(mid 0.275042 -0.275042)
							(end 0.2032 -0.3048)
						)
						(arc
							(start -0.2032 -0.3048)
							(mid -0.275042 -0.275042)
							(end -0.3048 -0.2032)
						)
						(arc
							(start -0.3048 0.2032)
							(mid -0.275042 0.275042)
							(end -0.2032 0.3048)
						)
						(arc
							(start 0.2032 0.3048)
							(mid 0.275042 0.275042)
							(end 0.3048 0.2032)
						)
					)
					(width 0)
					(fill yes)
				)
			)
		)
		(pad "2" smd custom
			(at 0 0.4445 90)
			(size 0.1524 0.1524)
			(layers "F.Cu" "F.Mask" "F.Paste")
			(net "GND")
			(options
				(clearance outline)
				(anchor circle)
			)
			(primitives
				(gr_poly
					(pts
						(arc
							(start 0.3048 -0.2032)
							(mid 0.275042 -0.275042)
							(end 0.2032 -0.3048)
						)
						(arc
							(start -0.2032 -0.3048)
							(mid -0.275042 -0.275042)
							(end -0.3048 -0.2032)
						)
						(arc
							(start -0.3048 0.2032)
							(mid -0.275042 0.275042)
							(end -0.2032 0.3048)
						)
						(arc
							(start 0.2032 0.3048)
							(mid 0.275042 0.275042)
							(end 0.3048 0.2032)
						)
					)
					(width 0)
					(fill yes)
				)
			)
		)
	)
)
